FILE_TYPE = CONNECTIVITY;
{Allegro Design Entry HDL 16.6-p007 (v16-6-112F) 10/10/2012}
"PAGE_NUMBER" = 215;
0"NC";
1"PVCCIO_CPU0\g";
2"GND\g";
3"GND\g";
4"GND\g";
5"GND\g";
6"P3V3_STBY\g";
7"GND\g";
8"GND\g";
9"GND\g";
10"GND\g";
11"GND\g";
12"GND\g";
13"P3V3_STBY\g";
14"PVCCIO_CPU0\g";
15"VR_PVDDQ_ABC_PWM1";
16"SVID_DIO1_CPU0_R";
17"PWRGD_PVDDQ_ABC";
18"SMB_VR_STBY_LVC3_SCL";
19"SMB_VR_STBY_LVC3_SDA";
20"VR_PVDDQ_ABC_VD12";
21"VR_PVDDQ_ABC_VDD";
22"IRQ_PVDDQ_ABC_VRHOT_LVT3_R_N";
23"PWRGD_PVDDQ_ABC_R";
24"VR_PVDDQ_ABC_XADDR2";
25"VR_PVDDQ_ABC_VD12";
26"SVID_VDIO_PVDDQ_ABC";
27"VR_PVDDQ_ABC_XADDR1";
28"VSENSE_PVDDQ_ABC_P";
29"FM_PVDDQ_ABC_EN";
30"SVID_ALERT_PVDDQ_ABC";
31"IRQ_PVDDQ_ABC_VRHOT_LVT3_N";
32"VR_PVDDQ_ABC_PWM2";
33"TP_PVDDQ_ABC_MP2";
34"SVID_ALERT1_CPU0_R_N";
35"PU_VR_PVDDQ_ABC_FAULT1";
36"TP_PVDDQ_ABC_MP1";
37"VSENSE_PVDDQ_ABC_N";
38"VR_PVDDQ_ABC_AVSP";
39"A_TSENSE_PVDDQ_ABC";
40"SVID_CLK1_CPU0_R";
41"VR_PVDDQ_ABC_VREN";
42"SVID_CLK_PVDDQ_ABC";
43"ISENSE_PVDDQ_ABC_PH1_IMON";
44"VR_PVDDQ_ABC_AIREF2";
45"VR_PVDDQ_ABC_AIREF1";
46"VR_PVDDQ_ABC_AIINSEN";
47"VR_PVDDQ_ABC_VINSEN";
48"ISENSE_PVDDQ_ABC_PH2_IMON";
%"RES"
"1","(-575,1025)","0","mstr_discrete","I12";
;
VALUE"10.0"
TOLERANCE"1%"
WATTAGE"1/16W"
LOCATION"R7G9"
MATERIAL"CHIP"
PACK_TYPE"0402"
PART_NUMBER"G21796-066"
CDS_SEC"1"
CDS_LOCATION"R7G9"
CDS_LIB"mstr_discrete"
ROOM"VDDQ_ABC_PWR_VR"
SEC_TYPE"0402"
SEC"1"
NO_XNET_CONNECTION"1";
"B"
$PN"2"38;
"A"
$PN"1"28;
%"RES"
"1","(-425,1300)","0","mstr_discrete","I13";
;
WATTAGE"1/16W"
TOLERANCE"5%"
VALUE"0.0"
LOCATION"R7F21"
PART_NUMBER"G21497-005"
PACK_TYPE"0402"
MATERIAL"CHIP"
CDS_SEC"1"
ROOM"PVCCIN_CPU0_VR"
CDS_LOCATION"R7F21"
CDS_LIB"mstr_discrete"
SEC"1"
SEC_TYPE"0402";
"B"
$PN"2"41;
"A"
$PN"1"29;
%"CAP"
"1","(-300,850)","0","mstr_discrete","I14";
;
VALUE"220PF"
TOLERANCE"10%"
MATERIAL"X7R"
VOLTAGE"50V"
PART_NUMBER"A36096-050"
PACK_TYPE"0402LF"
LOCATION"C7G4"
CDS_SEC"1"
CDS_LOCATION"C7G4"
CDS_LIB"mstr_discrete"
NO_XNET_CONNECTION"1"
SEC_TYPE"0402LF"
SEC"1"
ROOM"VDDQ_ABC_PWR_VR";
"A"
$PN"1"38;
"B"
$PN"2"37;
%"RES"
"1","(-250,2525)","0","mstr_discrete","I15";
;
GROUP"POWER_FAIR"
PACK_TYPE"0402"
MATERIAL"CHIP"
TOLERANCE"0.1%"
LOCATION"RF15"
WATTAGE"1/16W"
PART_NUMBER"G85996-004"
VALUE"1.0K"
FAIR_SS"064.9090D.M001"
SEC_TYPE"0402"
SEC"1"
ROOM"SB"
CDS_LIB"mstr_discrete"
CDS_LOCATION"RF15"
CDS_SEC"1";
"B"
$PN"2"43;
"A"
$PN"1"45;
%"SC22P50V2JN-4GP"
"1","(-275,2325)","1","w_hdl","I16";
;
GROUP"POWER_FAIR"
ATTRIBUTE"22PF"
RATED"50V"
TYPE"NPO"
TOLERANCE"5%"
PACK_SIZE"0402"
LOCATION"CF15"
VALUE"SC22P50V2JN-4GP"
PART_NUMBER"78.22034.1FL"
PACK_TYPE"SMD-BCG"
CDS_LMAN_SYM_OUTLINE"-50,25,50,-25"
CDS_LIB"w_hdl"
CDS_LOCATION"CF15"
$SEC"1"
CDS_SEC"1";
"2"
$PN"2"43;
"1"
$PN"1"45;
%"PVCCIO_CPU0"
"1","(450,3600)","0","mstr_symbols","I18";
;
HDL_POWER"PVCCIO_CPU0"
BODY_TYPE"PLUMBING"
CDS_LIB"mstr_symbols"
VOLTAGE"1.1V";
"G\NAC"1;
%"GND"
"1","(875,-150)","0","mstr_symbols","I19";
;
HDL_POWER"GND"
BODY_TYPE"PLUMBING"
ROOM"VDDQ_ABC_PWR_VR"
VOLTAGE"0"
CDS_LIB"mstr_symbols"
SIZE"1B";
"A\NAC"2;
%"GND"
"1","(1050,-300)","0","mstr_symbols","I20";
;
SIZE"1B"
VOLTAGE"0"
CDS_LIB"mstr_symbols"
ROOM"VDDQ_ABC_PWR_VR"
BODY_TYPE"PLUMBING"
HDL_POWER"GND";
"A\NAC"3;
%"CAP"
"1","(875,550)","2","mstr_discrete","I22";
;
VOLTAGE"50V"
LOCATION"C7G3"
TOLERANCE"10%"
MATERIAL"X7R"
PART_NUMBER"A36096-050"
PACK_TYPE"0402LF"
VALUE"220PF"
CDS_SEC"1"
CDS_LIB"mstr_discrete"
CDS_LOCATION"C7G3"
ROOM"VDDQ_ABC_PWR_VR"
SEC"1"
SEC_TYPE"0402LF";
"A"
$PN"1"39;
"B"
$PN"2"2;
%"GND"
"1","(950,650)","0","mstr_symbols","I23";
;
HDL_POWER"GND"
BODY_TYPE"PLUMBING"
ROOM"VDDQ_ABC_PWR_VR"
SIZE"1B"
CDS_LIB"mstr_symbols"
VOLTAGE"0";
"A\NAC"4;
%"GND"
"1","(1400,-300)","0","mstr_symbols","I24";
;
VOLTAGE"0"
CDS_LIB"mstr_symbols"
SIZE"1B"
ROOM"VDDQ_ABC_PWR_VR"
BODY_TYPE"PLUMBING"
HDL_POWER"GND";
"A\NAC"5;
%"SC22P50V2JN-4GP"
"1","(625,2450)","1","w_hdl","I26";
;
TOLERANCE"5%"
TYPE"NPO"
ATTRIBUTE"22PF"
LOCATION"CF16"
PACK_SIZE"0402"
RATED"50V"
VALUE"SC22P50V2JN-4GP"
BOM_SS"NOPOP"
GROUP"POWER_FAIR"
PACK_TYPE"SMD-BCG"
PART_NUMBER"78.22034.1FL"
CDS_LMAN_SYM_OUTLINE"-50,25,50,-25"
CDS_LIB"w_hdl"
CDS_LOCATION"CF16"
$SEC"1"
CDS_SEC"1";
"2"
$PN"2"48;
"1"
$PN"1"44;
%"RES"
"1","(650,2600)","0","mstr_discrete","I27";
;
LOCATION"RF16"
WATTAGE"1/16W"
MATERIAL"CHIP"
PACK_TYPE"0402"
TOLERANCE"0.1%"
PART_NUMBER"G85996-004"
VALUE"1.0K"
GROUP"POWER_FAIR"
BOM_SS"NOPOP"
CDS_SEC"1"
CDS_LOCATION"RF16"
CDS_LIB"mstr_discrete"
ROOM"SB"
SEC"1"
SEC_TYPE"0402";
"B"
$PN"2"48;
"A"
$PN"1"44;
%"RES"
"1","(675,2800)","0","mstr_discrete","I28";
;
TOLERANCE"1%"
PACK_TYPE"0402"
MATERIAL"CHIP"
LOCATION"R7G24"
PART_NUMBER"G21796-009"
VALUE"150.0"
WATTAGE"1/16W"
CDS_SEC"1"
CDS_LOCATION"R7G24"
CDS_LIB"mstr_discrete"
SEC_TYPE"0402"
SEC"1"
ROOM"VDDQ_ABC_PWR_VR";
"B"
$PN"2"42;
"A"
$PN"1"40;
%"RES"
"2","(975,3325)","0","mstr_discrete","I29";
;
PART_NUMBER"G21796-010"
PACK_TYPE"0402"
MATERIAL"EMPTY"
TOLERANCE"1%"
WATTAGE"1/16W"
VALUE"100.0K"
LOCATION"R7F20"
CDS_SEC"1"
CDS_LIB"mstr_discrete"
CDS_LOCATION"R7F20"
ROOM"BMC"
BOM_COST"SM_CONTROLLER"
SEC"1"
SEC_TYPE"0402";
"A"
$PN"1"6;
"B"
$PN"2"41;
%"P3V3_STBY"
"1","(1675,3675)","0","mstr_symbols","I30";
;
HDL_POWER"P3V3_STBY"
BODY_TYPE"PLUMBING"
VOLTAGE"3.3V"
CDS_LIB"mstr_symbols"
SIZE"1B";
"G\NAC"6;
%"GND"
"1","(1975,2700)","0","mstr_symbols","I31";
;
HDL_POWER"GND"
BODY_TYPE"PLUMBING"
ROOM"VDDQ_ABC_PWR_VR"
CDS_LIB"mstr_symbols"
SIZE"1B"
VOLTAGE"0";
"A\NAC"7;
%"GND"
"1","(2375,2700)","0","mstr_symbols","I32";
;
HDL_POWER"GND"
BODY_TYPE"PLUMBING"
VOLTAGE"0"
SIZE"1B"
CDS_LIB"mstr_symbols"
ROOM"VDDQ_ABC_PWR_VR";
"A\NAC"8;
%"RES"
"2","(1675,3250)","0","mstr_discrete","I33";
;
MATERIAL"CHIP"
PACK_TYPE"0402"
PART_NUMBER"G21497-005"
WATTAGE"1/16W"
TOLERANCE"5%"
VALUE"0.0"
LOCATION"R3T13"
CDS_SEC"1"
CDS_LIB"mstr_discrete"
ROOM"VDDQ_ABC_PWR_VR"
CDS_LOCATION"R3T13"
SEC"1"
SEC_TYPE"0402";
"A"
$PN"1"6;
"B"
$PN"2"21;
%"CAP_A"
"1","(1975,2900)","0","dev_discrete","I34";
;
PART_NUMBER"A36096-030"
PACK_TYPE"0402V"
VOLTAGE"16V"
TOLERANCE"10%"
MATERIAL"X7R"
VALUE"0.1UF"
LOCATION"C7F17"
CDS_LOCATION"C7F17"
CDS_LIB"dev_discrete"
ROOM"VDDQ_ABC_PWR_VR"
CDS_SEC"1"
SEC_TYPE"0402V"
SEC"1";
"B"
$PN"2"7;
"A"
$PN"1"21;
%"CAP_A"
"1","(2375,2900)","0","dev_discrete","I35";
;
VOLTAGE"6.3V"
TOLERANCE"10%"
MATERIAL"X6S"
LOCATION"C7F18"
VALUE"1.0UF"
PACK_TYPE"0402V"
PART_NUMBER"D97712-004"
CDS_SEC"1"
CDS_LIB"dev_discrete"
CDS_LOCATION"C7F18"
ROOM"VDDQ_ABC_PWR_VR"
SEC"1"
SEC_TYPE"0402V";
"B"
$PN"2"8;
"A"
$PN"1"21;
%"GND"
"1","(2850,625)","0","mstr_symbols","I36";
;
HDL_POWER"GND"
BODY_TYPE"PLUMBING"
ROOM"VDDQ_ABC_PWR_VR"
CDS_LIB"mstr_symbols"
SIZE"1B"
VOLTAGE"0";
"A\NAC"9;
%"GND"
"1","(3150,0)","0","mstr_symbols","I37";
;
HDL_POWER"GND"
BODY_TYPE"PLUMBING"
ROOM"VDDQ_ABC_PWR_VR"
SIZE"1B"
VOLTAGE"0"
CDS_LIB"mstr_symbols";
"A\NAC"10;
%"CAP_A"
"1","(3150,200)","0","dev_discrete","I38";
;
MATERIAL"X7R"
TOLERANCE"10%"
VOLTAGE"16V"
PACK_TYPE"0402V"
PART_NUMBER"A36096-030"
VALUE"0.1UF"
LOCATION"C7F15"
CDS_LIB"dev_discrete"
ROOM"VDDQ_ABC_PWR_VR"
CDS_LOCATION"C7F15"
CDS_SEC"1"
SEC_TYPE"0402V"
SEC"1";
"B"
$PN"2"10;
"A"
$PN"1"25;
%"GND"
"1","(3550,-75)","0","mstr_symbols","I39";
;
HDL_POWER"GND"
BODY_TYPE"PLUMBING"
ROOM"VDDQ_ABC_PWR_VR"
VOLTAGE"0"
CDS_LIB"mstr_symbols"
SIZE"1B";
"A\NAC"11;
%"CAP_A"
"1","(3550,200)","0","dev_discrete","I40";
;
MATERIAL"X6S"
TOLERANCE"10%"
PART_NUMBER"D97712-004"
LOCATION"C7F16"
PACK_TYPE"0402V"
VALUE"1.0UF"
VOLTAGE"6.3V"
CDS_LIB"dev_discrete"
CDS_LOCATION"C7F16"
CDS_SEC"1"
SEC_TYPE"0402V"
SEC"1"
ROOM"VDDQ_ABC_PWR_VR";
"B"
$PN"2"11;
"A"
$PN"1"25;
%"RES"
"1","(3625,1500)","0","mstr_discrete","I41";
;
TOLERANCE"5%"
LOCATION"R7G2"
VALUE"0.0"
PART_NUMBER"G21497-005"
PACK_TYPE"0402"
WATTAGE"1/16W"
MATERIAL"CHIP"
CDS_SEC"1"
SEC_TYPE"0402"
SEC"1"
CDS_LOCATION"R7G2"
ROOM"VDDQ_ABC_PWR_VR"
CDS_LIB"mstr_discrete";
"B"
$PN"2"16;
"A"
$PN"1"26;
%"GND"
"1","(3800,775)","0","mstr_symbols","I43";
;
HDL_POWER"GND"
BODY_TYPE"PLUMBING"
ROOM"VDDQ_ABC_PWR_VR"
CDS_LIB"mstr_symbols"
SIZE"1B"
VOLTAGE"0";
"A\NAC"12;
%"CAP"
"1","(3800,1050)","0","mstr_discrete","I44";
;
MATERIAL"X7R"
TOLERANCE"10%"
PACK_TYPE"0402LF"
PART_NUMBER"A36096-046"
VOLTAGE"50V"
VALUE"1000PF"
LOCATION"C7F14"
CDS_SEC"1"
CDS_LOCATION"C7F14"
CDS_LIB"mstr_discrete"
ROOM"VDDQ_ABC_PWR_VR"
SEC"1"
SEC_TYPE"0402LF";
"A"
$PN"1"23;
"B"
$PN"2"12;
%"RES"
"1","(4000,1650)","0","mstr_discrete","I45";
;
MATERIAL"EMPTY"
WATTAGE"1/16W"
LOCATION"R12W26"
VALUE"0.0"
TOLERANCE"5%"
PACK_TYPE"0402"
PART_NUMBER"G21497-005"
CDS_LIB"mstr_discrete"
SEC"1"
ROOM"NV_DIMM"
SEC_TYPE"0402"
BOM_COST"MEM_NV"
CDS_LOCATION"R12W26"
CDS_SEC"1";
"B"
$PN"2"17;
"A"
$PN"1"36;
%"RES"
"1","(3475,2200)","0","mstr_discrete","I49";
;
TOLERANCE"5%"
MATERIAL"CHIP"
PART_NUMBER"G21497-005"
WATTAGE"1/16W"
PACK_TYPE"0402"
LOCATION"R7G4"
VALUE"0.0"
CDS_SEC"1"
CDS_LIB"mstr_discrete"
CDS_LOCATION"R7G4"
ROOM"VDDQ_ABC_PWR_VR"
SEC"1"
SEC_TYPE"0402";
"B"
$PN"2"34;
"A"
$PN"1"30;
%"RES"
"2","(2950,2900)","0","mstr_discrete","I50";
;
PART_NUMBER"G21796-026"
LOCATION"R7F27"
PACK_TYPE"0402"
TOLERANCE"1%"
VALUE"1.00K"
MATERIAL"CHIP"
WATTAGE"1/16W"
CDS_SEC"1"
CDS_LIB"mstr_discrete"
CDS_LOCATION"R7F27"
SEC_TYPE"0402"
SEC"1"
ROOM"VDDQ_ABC_PWR_VR";
"A"
$PN"1"13;
"B"
$PN"2"22;
%"RES"
"2","(3300,2900)","0","mstr_discrete","I51";
;
PART_NUMBER"G21796-026"
LOCATION"R7F22"
TOLERANCE"1%"
VALUE"1.00K"
MATERIAL"CHIP"
PACK_TYPE"0402"
WATTAGE"1/16W"
CDS_SEC"1"
CDS_LIB"mstr_discrete"
CDS_LOCATION"R7F22"
SEC"1"
SEC_TYPE"0402"
ROOM"VDDQ_ABC_PWR_VR";
"A"
$PN"1"13;
"B"
$PN"2"23;
%"P3V3_STBY"
"1","(3500,3575)","0","mstr_symbols","I52";
;
HDL_POWER"P3V3_STBY"
BODY_TYPE"PLUMBING"
VOLTAGE"3.3V"
SIZE"1B"
CDS_LIB"mstr_symbols";
"G\NAC"13;
%"RES"
"1","(3975,2250)","0","mstr_discrete","I53";
;
LOCATION"R7F23"
PART_NUMBER"G21796-074"
WATTAGE"1/16W"
TOLERANCE"1%"
MATERIAL"CHIP"
VALUE"33.2"
PACK_TYPE"0402"
CDS_SEC"1"
CDS_LIB"mstr_discrete"
CDS_LOCATION"R7F23"
SEC"1"
SEC_TYPE"0402";
"B"
$PN"2"31;
"A"
$PN"1"22;
%"RES"
"1","(4000,2050)","0","mstr_discrete","I54";
;
LOCATION"R12W27"
PART_NUMBER"G21497-005"
TOLERANCE"5%"
VALUE"0.0"
PACK_TYPE"0402"
WATTAGE"1/16W"
MATERIAL"EMPTY"
CDS_SEC"1"
CDS_LOCATION"R12W27"
BOM_COST"MEM_NV"
SEC_TYPE"0402"
ROOM"NV_DIMM"
SEC"1"
CDS_LIB"mstr_discrete";
"B"
$PN"2"17;
"A"
$PN"1"33;
%"RES"
"1","(4050,2350)","0","mstr_discrete","I56";
;
TOLERANCE"1.0%"
PACK_TYPE"0402"
PART_NUMBER"G21796-250"
VALUE"22.1"
MATERIAL"CHIP"
POP"NOPOP"
WATTAGE"1/16W"
LOCATION"R7F24"
CDS_SEC"1"
ROOM"VDDQ_ABC_PWR_VR"
CDS_LOCATION"R7F24"
CDS_LIB"mstr_discrete"
SEC"1"
SEC_TYPE"0402";
"B"
$PN"2"17;
"A"
$PN"1"23;
%"RES"
"2","(4750,2650)","0","mstr_discrete","I58";
;
LOCATION"R3U2"
MATERIAL"CHIP"
WATTAGE"1/16W"
TOLERANCE"1%"
VALUE"100.0"
PACK_TYPE"0402"
PART_NUMBER"G21796-017"
CDS_SEC"1"
CDS_LIB"mstr_discrete"
CDS_LOCATION"R3U2"
SEC_TYPE"0402"
SEC"1"
ROOM"VDDQ_ABC_PWR_VR";
"A"
$PN"1"14;
"B"
$PN"2"16;
%"PVCCIO_CPU0"
"1","(4750,2850)","0","mstr_symbols","I59";
;
HDL_POWER"PVCCIO_CPU0"
BODY_TYPE"PLUMBING"
VOLTAGE"1.1V"
CDS_LIB"mstr_symbols";
"G\NAC"14;
%"PXM1310B"
"2","(2275,1600)","0","mstr_controller","I69";
;
PART_NUMBER"H89186-001"
LOCATION"EU7G1"
MATERIAL"IC"
CDS_LMAN_SYM_OUTLINE"-400,900,400,-900"
CDS_LIB"mstr_controller"
PACK_TYPE"QFN"
CDS_SEC"1"
$SEC"1"
CDS_LOCATION"EU7G1";
"MP2"
$PN"18"33;
"THPAD"
$PN"41"9;
"BPWM1"
$PN"1"0;
"APWM1"
$PN"5"15;
"APWM2"
$PN"4"32;
"APWM3"
$PN"3"0;
"SDA"
$PN"6"19;
"SCL"
$PN"7"18;
"VCLK"
$PN"15"42;
"VDIO"
$PN"16"26;
"RESET_N \B"
$PN"8"0;
"XADDR1"
$PN"36"27;
"AISEN3"
$PN"26"0;
"AIREF3"
$PN"25"0;
"XADDR2"
$PN"33"24;
"AISEN2"
$PN"24"48;
"AIREF2"
$PN"23"44;
"ATSEN"
$PN"35"39;
"AISEN1"
$PN"22"43;
"AIREF1"
$PN"21"45;
"VDD"
$PN"39"21;
"BTSEN"
$PN"34"0;
"BISEN1"
$PN"32"4;
"BIREF1"
$PN"31"0;
"DNC<0>"
$PN"2"0;
"DNC<1>"
$PN"28"0;
"VRHOT_N \B"
$PN"11"22;
"PINALRT_N \B"
$PN"12"0;
"VALRT_N \B"
$PN"17"30;
"AVSEN"
$PN"19"38;
"AVREF"
$PN"20"37;
"BVSEN"
$PN"29"0;
"BVREF"
$PN"30"0;
"VINSEN"
$PN"37"47;
"VD12"
$PN"40"20;
"GND"
$PN"27"9;
"IINSEN"
$PN"38"46;
"AVRRDY"
$PN"9"23;
"AVREN"
$PN"10"41;
"MP0"
$PN"13"35;
"MP1"
$PN"14"36;
%"RES"
"2","(450,3325)","0","mstr_discrete","I70";
;
VALUE"49.9"
PACK_TYPE"0402"
MATERIAL"CHIP"
WATTAGE"1/16W"
TOLERANCE"1%"
PART_NUMBER"G21796-047"
LOCATION"R3T11"
SEC_TYPE"0402"
SEC"1"
CDS_LIB"mstr_discrete"
ROOM"VDDQ_DEF_PWR_VR"
CDS_SEC"1"
CDS_LOCATION"R3T11";
"A"
$PN"1"1;
"B"
$PN"2"40;
%"RES"
"2","(1050,-50)","0","mstr_discrete","I72";
;
CDS_SEC"1"
MATERIAL"CHIP"
WATTAGE"1/16W"
VALUE"2.26K"
PACK_TYPE"0402"
TOLERANCE"1.0%"
POP"NOPOP"
PART_NUMBER"G21796-311"
LOCATION"R7G8"
CDS_LOCATION"R7G8"
CDS_LIB"mstr_discrete"
SKU"B"
ROOM"SMBUS"
BOM_COST"SM_CONTROLLER"
SEC"1"
SEC_TYPE"0402";
"A"
$PN"1"27;
"B"
$PN"2"3;
%"RES"
"2","(1400,-50)","0","mstr_discrete","I73";
;
CDS_SEC"1"
VALUE"2.26K"
PACK_TYPE"0402"
LOCATION"R7G10"
WATTAGE"1/16W"
TOLERANCE"1.0%"
MATERIAL"CHIP"
PART_NUMBER"G21796-311"
CDS_LIB"mstr_discrete"
SKU"B"
ROOM"SMBUS"
BOM_COST"SM_CONTROLLER"
SEC"1"
SEC_TYPE"0402"
CDS_LOCATION"R7G10";
"A"
$PN"1"24;
"B"
$PN"2"5;
%"RES"
"1","(4000,1700)","0","mstr_discrete","I74";
;
CDS_SEC"1"
WATTAGE"1/16W"
PACK_TYPE"0402"
LOCATION"R12W25"
TOLERANCE"5%"
VALUE"0.0"
PART_NUMBER"G21497-005"
CDS_LIB"mstr_discrete"
BOM_COST"PROC_SIDEBAND"
MATERIAL"CHIP"
ROOM"CPU0"
SEC_TYPE"0402"
SEC"1"
CDS_LOCATION"R12W25";
"B"
$PN"2"17;
"A"
$PN"1"35;
%"RES"
"2","(4300,2900)","0","mstr_discrete","I75";
;
CDS_SEC"1"
PART_NUMBER"G21796-311"
TOLERANCE"1.0%"
PACK_TYPE"0402"
LOCATION"R7F36"
VALUE"2.26K"
MATERIAL"CHIP"
WATTAGE"1/16W"
CDS_LIB"mstr_discrete"
SKU"B"
ROOM"SMBUS"
BOM_COST"SM_CONTROLLER"
SEC"1"
SEC_TYPE"0402"
CDS_LOCATION"R7F36";
"A"
$PN"1"13;
"B"
$PN"2"17;
END.
